FILE_TYPE = CONNECTIVITY;
{Allegro Design Entry HDL 17.4-2019 S026 (4007227) 1/17/2022}
"PAGE_NUMBER" = 327;
0"NC";
1"P5E_CPU0_P3_RX_BUF_DP<7>";
2"P5E_CPU0_P2_TX_BUF_C_DN<7>";
3"UART_BMC_BIC_TX";
4"PRSNT_CABLE_GPU_A1_N";
5"P5E_CPU0_P3_TX_BUF_C_DP<7>";
6"P5E_CPU0_P3_TX_BUF_C_DN<7>";
7"P5E_CPU0_P2_TX_BUF_C_DP<7>";
8"GND\g";
9"P5E_CPU0_P2_TX_BUF_C_DP<3>";
10"P5E_CPU0_P2_RX_BUF_DP<2>";
11"P5E_CPU0_P2_TX_BUF_C_DP<2>";
12"P5E_CPU0_P2_TX_BUF_C_DP<0>";
13"P5E_CPU0_P2_TX_BUF_C_DN<0>";
14"P5E_CPU0_P3_RX_BUF_DP<0>";
15"P5E_CPU0_P3_RX_BUF_DN<0>";
16"P5E_CPU0_P2_RX_BUF_DP<0>";
17"PRSNT_CABLE_SWB_B1_N";
18"P5E_CPU0_P3_TX_BUF_C_DP<0>";
19"FM_SWB_PWRGD";
20"P5E_CPU0_P3_RX_BUF_DN<2>";
21"P5E_CPU0_P3_RX_BUF_DP<2>";
22"P5E_CPU0_P2_TX_BUF_C_DN<2>";
23"P5E_CPU0_P3_TX_BUF_C_DP<2>";
24"P5E_CPU0_P2_RX_BUF_DN<1>";
25"P5E_CPU0_P2_RX_BUF_DN<0>";
26"GND\g";
27"P5E_CPU0_P3_TX_BUF_C_DN<0>";
28"P5E_CPU0_P3_TX_BUF_C_DP<1>";
29"I3C_BMC_SWB_BUF_SDA";
30"P5E_CPU0_P3_TX_BUF_C_DN<1>";
31"P5E_CPU0_P2_TX_BUF_C_DP<1>";
32"P5E_CPU0_P3_TX_BUF_C_DN<2>";
33"P5E_CPU0_P2_RX_BUF_DP<1>";
34"P5E_CPU0_P2_RX_BUF_DN<2>";
35"I3C_BMC_SWB_BUF_SCL";
36"P5E_CPU0_P3_TX_BUF_C_DP<3>";
37"P5E_CPU0_P3_TX_BUF_C_DN<3>";
38"P5E_CPU0_P2_TX_BUF_C_DP<4>";
39"P5E_CPU0_P3_TX_BUF_C_DP<4>";
40"P5E_CPU0_P3_TX_BUF_C_DN<4>";
41"P5E_CPU0_P2_RX_BUF_DP<4>";
42"P5E_CPU0_P3_RX_BUF_DP<4>";
43"P5E_CPU0_P2_TX_BUF_C_DN<3>";
44"P5E_CPU0_P3_RX_BUF_DP<3>";
45"P5E_CPU0_P2_RX_BUF_DP<3>";
46"P5E_CPU0_P2_RX_BUF_DN<3>";
47"P5E_CPU0_P3_RX_BUF_DN<3>";
48"NC_J106_A5";
49"P5E_CPU0_P2_RX_BUF_DN<4>";
50"UART_BMC_BIC_RX";
51"P5E_CPU0_P3_TX_BUF_C_DP<5>";
52"P5E_CPU0_P3_RX_BUF_DP<5>";
53"P5E_CPU0_P2_RX_BUF_DP<5>";
54"P5E_CPU0_P2_RX_BUF_DN<5>";
55"P5E_CPU0_P3_TX_BUF_C_DP<6>";
56"P5E_CPU0_P2_TX_BUF_C_DN<6>";
57"P5E_CPU0_P3_RX_BUF_DP<6>";
58"P5E_CPU0_P3_RX_BUF_DN<6>";
59"P5E_CPU0_P2_RX_BUF_DP<6>";
60"P5E_CPU0_P2_RX_BUF_DN<6>";
61"P5E_CPU0_P2_TX_BUF_C_DP<6>";
62"P5E_CPU0_P3_RX_BUF_DN<5>";
63"P5E_CPU0_P2_TX_BUF_C_DN<5>";
64"P5E_CPU0_P2_TX_BUF_C_DP<5>";
65"P5E_CPU0_P3_TX_BUF_C_DN<5>";
66"P5E_CPU0_P2_TX_BUF_C_DN<4>";
67"P5E_CPU0_P3_TX_BUF_C_DN<6>";
68"P5E_CPU0_P3_RX_BUF_DP<1>";
69"P5E_CPU0_P2_TX_BUF_C_DN<1>";
70"P5E_CPU0_P3_RX_BUF_DN<1>";
71"P5E_CPU0_P3_RX_BUF_DN<4>";
72"P5E_CPU0_P3_RX_BUF_DN<7>";
73"P5E_CPU0_P2_RX_BUF_DP<7>";
74"P5E_CPU0_P2_RX_BUF_DN<7>";
%"UNIVERSAL_GND"
"1","(-1100,2150)","0","pure_quanta_power","I18";
;
CDS_LIB"pure_quanta_power"
HDL_POWER"GND";
"A"8;
%"CONN112_10137002101LF"
"1","(0,4050)","0","pure_quanta","I19";
;
LOCATION"J106"
$SEC"1"
CDS_SEC"1"
PART_TYPE"THLF"
MATERIAL"IO"
VALUE"CONN112_10137002-101LF"
CDS_LMAN_SYM_OUTLINE"-775,1650,775,-1650"
NEEDS_NO_SIZE"TRUE"
CDS_LIB"pure_quanta"
PART_NUMBER"DFHSB2FR012";
"N8"
$PN"N8"3;
"M8"
$PN"M8"8;
"N7"
$PN"N7"8;
"M7"
$PN"M7"55;
"N6"
$PN"N6"50;
"M6"
$PN"M6"8;
"N5"
$PN"N5"8;
"M5"
$PN"M5"39;
"L5"
$PN"L5"40;
"L6"
$PN"L6"51;
"L7"
$PN"L7"67;
"L8"
$PN"L8"5;
"K5"
$PN"K5"8;
"K6"
$PN"K6"65;
"K7"
$PN"K7"8;
"K8"
$PN"K8"6;
"J5"
$PN"J5"38;
"J6"
$PN"J6"8;
"J7"
$PN"J7"61;
"J8"
$PN"J8"8;
"I5"
$PN"I5"66;
"I6"
$PN"I6"64;
"I7"
$PN"I7"56;
"I8"
$PN"I8"7;
"H5"
$PN"H5"8;
"H6"
$PN"H6"63;
"H7"
$PN"H7"8;
"H8"
$PN"H8"2;
"G5"
$PN"G5"42;
"G6"
$PN"G6"8;
"G7"
$PN"G7"57;
"G8"
$PN"G8"8;
"F5"
$PN"F5"71;
"F6"
$PN"F6"52;
"F7"
$PN"F7"58;
"F8"
$PN"F8"1;
"E5"
$PN"E5"8;
"E6"
$PN"E6"62;
"E7"
$PN"E7"8;
"E8"
$PN"E8"72;
"D5"
$PN"D5"41;
"D6"
$PN"D6"8;
"D7"
$PN"D7"59;
"D8"
$PN"D8"8;
"C5"
$PN"C5"49;
"C6"
$PN"C6"53;
"C7"
$PN"C7"60;
"C8"
$PN"C8"73;
"B5"
$PN"B5"8;
"B6"
$PN"B6"54;
"B7"
$PN"B7"8;
"B8"
$PN"B8"74;
"A5"
$PN"A5"48;
"A6"
$PN"A6"8;
"A7"
$PN"A7"4;
"A8"
$PN"A8"8;
%"UNIVERSAL_GND"
"1","(3475,2025)","0","pure_quanta_power","I55";
;
CDS_LIB"pure_quanta_power"
HDL_POWER"GND";
"A"26;
%"CONN112_10137002101LF"
"2","(4625,3975)","0","pure_quanta","I74";
;
LOCATION"J106"
$SEC"2"
CDS_SEC"2"
PART_TYPE"THLF"
MATERIAL"IO"
CDS_LMAN_SYM_OUTLINE"-775,1650,775,-1650"
NEEDS_NO_SIZE"TRUE"
CDS_LIB"pure_quanta"
VALUE"CONN112_10137002-101LF"
PART_NUMBER"DFHSB2FR012";
"N4"
$PN"N4"35;
"M4"
$PN"M4"26;
"N3"
$PN"N3"26;
"M3"
$PN"M3"23;
"N2"
$PN"N2"29;
"M2"
$PN"M2"26;
"N1"
$PN"N1"26;
"M1"
$PN"M1"18;
"L1"
$PN"L1"27;
"L2"
$PN"L2"28;
"L3"
$PN"L3"32;
"L4"
$PN"L4"36;
"K1"
$PN"K1"26;
"K2"
$PN"K2"30;
"K3"
$PN"K3"26;
"K4"
$PN"K4"37;
"J1"
$PN"J1"12;
"J2"
$PN"J2"26;
"J3"
$PN"J3"11;
"J4"
$PN"J4"26;
"I1"
$PN"I1"13;
"I2"
$PN"I2"31;
"I3"
$PN"I3"22;
"I4"
$PN"I4"9;
"H1"
$PN"H1"26;
"H2"
$PN"H2"69;
"H3"
$PN"H3"26;
"H4"
$PN"H4"43;
"G1"
$PN"G1"14;
"G2"
$PN"G2"26;
"G3"
$PN"G3"21;
"G4"
$PN"G4"26;
"F1"
$PN"F1"15;
"F2"
$PN"F2"68;
"F3"
$PN"F3"20;
"F4"
$PN"F4"44;
"E1"
$PN"E1"26;
"E2"
$PN"E2"70;
"E3"
$PN"E3"26;
"E4"
$PN"E4"47;
"D1"
$PN"D1"16;
"D2"
$PN"D2"26;
"D3"
$PN"D3"10;
"D4"
$PN"D4"26;
"C1"
$PN"C1"25;
"C2"
$PN"C2"33;
"C3"
$PN"C3"34;
"C4"
$PN"C4"45;
"B1"
$PN"B1"26;
"B2"
$PN"B2"24;
"B3"
$PN"B3"26;
"B4"
$PN"B4"46;
"A1"
$PN"A1"17;
"A2"
$PN"A2"26;
"A3"
$PN"A3"19;
"A4"
$PN"A4"26;
END.
